(kicad_pcb
	(version 20260206)
	(generator "pcbnew")
	(generator_version "10.0")
	(general
		(thickness 1.6)
		(legacy_teardrops no)
	)
	(paper "A4")
	(title_block
		(title "03242023_DA0F0TMBIJ0_F0T_Motherboard_J_brd_V01_OCP.brd")
		(comment 1 "Grand Teton / footprints 2214-2220 of 6105")
	)
	(layers
		(0 "F.Cu" signal "TOP")
		(4 "In1.Cu" signal "GND")
		(6 "In2.Cu" signal "IN1")
		(8 "In3.Cu" signal "GND1")
		(10 "In4.Cu" signal "IN2")
		(12 "In5.Cu" signal "GND2")
		(14 "In6.Cu" signal "IN3")
		(16 "In7.Cu" signal "GND3")
		(18 "In8.Cu" signal "VCC")
		(20 "In9.Cu" signal "VCC1")
		(22 "In10.Cu" signal "GND4")
		(24 "In11.Cu" signal "IN4")
		(26 "In12.Cu" signal "GND5")
		(28 "In13.Cu" signal "IN5")
		(30 "In14.Cu" signal "GND6")
		(32 "In15.Cu" signal "IN6")
		(34 "In16.Cu" signal "GND7")
		(2 "B.Cu" signal "BOTTOM")
		(9 "F.Adhes" user "F.Adhesive")
		(11 "B.Adhes" user "B.Adhesive")
		(13 "F.Paste" user "Package Geometry/Pastemask Top")
		(15 "B.Paste" user "Package Geometry/Pastemask Bottom")
		(5 "F.SilkS" user "Ref Des/Silkscreen Top")
		(7 "B.SilkS" user "Ref Des/Silkscreen Bottom")
		(1 "F.Mask" user "Board Geometry/Soldermask Top")
		(3 "B.Mask" user "Board Geometry/Soldermask Bottom")
		(17 "Dwgs.User" user "User.Drawings")
		(19 "Cmts.User" user "User.Comments")
		(21 "Eco1.User" user "User.Eco1")
		(23 "Eco2.User" user "User.Eco2")
		(25 "Edge.Cuts" user "Board Geometry/Outline")
		(27 "Margin" user)
		(31 "F.CrtYd" user "Package Geometry/Place Bound Top")
		(29 "B.CrtYd" user "Package Geometry/Place Bound Bottom")
		(35 "F.Fab" user "Ref Des/Assembly Top")
		(33 "B.Fab" user "Ref Des/Assembly Bottom")
	)
	(footprint ""
		(layer "F.Cu")
		(at 21.181314 -95.510604)
		(property "Reference" "R3664"
			(at 0 0 0)
			(layer "F.SilkS")
			(hide yes)
			(effects
				(font
					(size 1.27 1.27)
				)
			)
		)
		(property "Value" ""
			(at 0 0 0)
			(layer "F.Fab")
			(effects
				(font
					(size 1.27 1.27)
				)
			)
		)
		(duplicate_pad_numbers_are_jumpers no)
		(fp_line
			(start -0.7874 -0.4064)
			(end 0.7874 -0.4064)
			(stroke
				(width 0.1524)
				(type default)
			)
			(layer "F.SilkS")
		)
		(fp_line
			(start -0.7874 0.4064)
			(end -0.7874 -0.4064)
			(stroke
				(width 0.1524)
				(type default)
			)
			(layer "F.SilkS")
		)
		(fp_line
			(start 0.7874 -0.4064)
			(end 0.7874 0.4064)
			(stroke
				(width 0.1524)
				(type default)
			)
			(layer "F.SilkS")
		)
		(fp_line
			(start 0.7874 0.4064)
			(end -0.7874 0.4064)
			(stroke
				(width 0.1524)
				(type default)
			)
			(layer "F.SilkS")
		)
		(fp_line
			(start -0.67945 -0.305054)
			(end -0.12065 -0.305054)
			(stroke
				(width 0.1)
				(type default)
			)
			(layer "F.Fab")
		)
		(fp_line
			(start -0.67945 0.3048)
			(end -0.67945 -0.305054)
			(stroke
				(width 0.1)
				(type default)
			)
			(layer "F.Fab")
		)
		(fp_line
			(start -0.12065 -0.305054)
			(end -0.12065 -0.2794)
			(stroke
				(width 0.1)
				(type default)
			)
			(layer "F.Fab")
		)
		(fp_line
			(start -0.12065 -0.2794)
			(end 0.12065 -0.2794)
			(stroke
				(width 0.1)
				(type default)
			)
			(layer "F.Fab")
		)
		(fp_line
			(start -0.12065 0.2794)
			(end -0.12065 0.3048)
			(stroke
				(width 0.1)
				(type default)
			)
			(layer "F.Fab")
		)
		(fp_line
			(start -0.12065 0.3048)
			(end -0.67945 0.3048)
			(stroke
				(width 0.1)
				(type default)
			)
			(layer "F.Fab")
		)
		(fp_line
			(start 0.120396 0.2794)
			(end -0.12065 0.2794)
			(stroke
				(width 0.1)
				(type default)
			)
			(layer "F.Fab")
		)
		(fp_line
			(start 0.120396 0.3048)
			(end 0.120396 0.2794)
			(stroke
				(width 0.1)
				(type default)
			)
			(layer "F.Fab")
		)
		(fp_line
			(start 0.12065 -0.3048)
			(end 0.67945 -0.3048)
			(stroke
				(width 0.1)
				(type default)
			)
			(layer "F.Fab")
		)
		(fp_line
			(start 0.12065 -0.2794)
			(end 0.12065 -0.3048)
			(stroke
				(width 0.1)
				(type default)
			)
			(layer "F.Fab")
		)
		(fp_line
			(start 0.67945 -0.3048)
			(end 0.67945 0.3048)
			(stroke
				(width 0.1)
				(type default)
			)
			(layer "F.Fab")
		)
		(fp_line
			(start 0.67945 0.3048)
			(end 0.120396 0.3048)
			(stroke
				(width 0.1)
				(type default)
			)
			(layer "F.Fab")
		)
		(pad "1" smd circle
			(at -0.40005 0)
			(size 0 0)
			(layers "F.Cu" "F.Mask" "F.Paste")
			(net "USB_HUB_PSELF")
		)
		(pad "2" smd circle
			(at 0.40005 0)
			(size 0 0)
			(layers "F.Cu" "F.Mask" "F.Paste")
			(net "GND")
		)
	)
	(footprint ""
		(layer "F.Cu")
		(at 441.376054 -123.656598)
		(property "Reference" "C2444"
			(at 0 0 0)
			(layer "F.SilkS")
			(hide yes)
			(effects
				(font
					(size 1.27 1.27)
				)
			)
		)
		(property "Value" ""
			(at 0 0 0)
			(layer "F.Fab")
			(effects
				(font
					(size 1.27 1.27)
				)
			)
		)
		(duplicate_pad_numbers_are_jumpers no)
		(fp_line
			(start -0.7874 -0.4064)
			(end 0.7874 -0.4064)
			(stroke
				(width 0.1524)
				(type default)
			)
			(layer "F.SilkS")
		)
		(fp_line
			(start -0.7874 0.4064)
			(end -0.7874 -0.4064)
			(stroke
				(width 0.1524)
				(type default)
			)
			(layer "F.SilkS")
		)
		(fp_line
			(start 0.7874 -0.4064)
			(end 0.7874 0.4064)
			(stroke
				(width 0.1524)
				(type default)
			)
			(layer "F.SilkS")
		)
		(fp_line
			(start 0.7874 0.4064)
			(end -0.7874 0.4064)
			(stroke
				(width 0.1524)
				(type default)
			)
			(layer "F.SilkS")
		)
		(fp_line
			(start -0.67945 -0.305054)
			(end -0.12065 -0.305054)
			(stroke
				(width 0.1)
				(type default)
			)
			(layer "F.Fab")
		)
		(fp_line
			(start -0.67945 0.3048)
			(end -0.67945 -0.305054)
			(stroke
				(width 0.1)
				(type default)
			)
			(layer "F.Fab")
		)
		(fp_line
			(start -0.12065 -0.305054)
			(end -0.12065 -0.2794)
			(stroke
				(width 0.1)
				(type default)
			)
			(layer "F.Fab")
		)
		(fp_line
			(start -0.12065 -0.2794)
			(end 0.12065 -0.2794)
			(stroke
				(width 0.1)
				(type default)
			)
			(layer "F.Fab")
		)
		(fp_line
			(start -0.12065 0.2794)
			(end -0.12065 0.3048)
			(stroke
				(width 0.1)
				(type default)
			)
			(layer "F.Fab")
		)
		(fp_line
			(start -0.12065 0.3048)
			(end -0.67945 0.3048)
			(stroke
				(width 0.1)
				(type default)
			)
			(layer "F.Fab")
		)
		(fp_line
			(start 0.120396 0.2794)
			(end -0.12065 0.2794)
			(stroke
				(width 0.1)
				(type default)
			)
			(layer "F.Fab")
		)
		(fp_line
			(start 0.120396 0.3048)
			(end 0.120396 0.2794)
			(stroke
				(width 0.1)
				(type default)
			)
			(layer "F.Fab")
		)
		(fp_line
			(start 0.12065 -0.3048)
			(end 0.67945 -0.3048)
			(stroke
				(width 0.1)
				(type default)
			)
			(layer "F.Fab")
		)
		(fp_line
			(start 0.12065 -0.2794)
			(end 0.12065 -0.3048)
			(stroke
				(width 0.1)
				(type default)
			)
			(layer "F.Fab")
		)
		(fp_line
			(start 0.67945 -0.3048)
			(end 0.67945 0.3048)
			(stroke
				(width 0.1)
				(type default)
			)
			(layer "F.Fab")
		)
		(fp_line
			(start 0.67945 0.3048)
			(end 0.120396 0.3048)
			(stroke
				(width 0.1)
				(type default)
			)
			(layer "F.Fab")
		)
		(pad "1" smd circle
			(at -0.40005 0)
			(size 0 0)
			(layers "F.Cu" "F.Mask" "F.Paste")
			(net "PVNN_TERM_CPU0")
		)
		(pad "2" smd circle
			(at 0.40005 0)
			(size 0 0)
			(layers "F.Cu" "F.Mask" "F.Paste")
			(net "GND")
		)
	)
	(footprint ""
		(layer "F.Cu")
		(at 294.62222 -419.02761 -90)
		(property "Reference" "R4154"
			(at 0 0 270)
			(layer "F.SilkS")
			(hide yes)
			(effects
				(font
					(size 1.27 1.27)
				)
			)
		)
		(property "Value" ""
			(at 0 0 270)
			(layer "F.Fab")
			(effects
				(font
					(size 1.27 1.27)
				)
			)
		)
		(duplicate_pad_numbers_are_jumpers no)
		(fp_line
			(start -0.7874 0.4064)
			(end -0.7874 -0.4064)
			(stroke
				(width 0.1524)
				(type default)
			)
			(layer "F.SilkS")
		)
		(fp_line
			(start 0.7874 0.4064)
			(end -0.7874 0.4064)
			(stroke
				(width 0.1524)
				(type default)
			)
			(layer "F.SilkS")
		)
		(fp_line
			(start -0.7874 -0.4064)
			(end 0.7874 -0.4064)
			(stroke
				(width 0.1524)
				(type default)
			)
			(layer "F.SilkS")
		)
		(fp_line
			(start 0.7874 -0.4064)
			(end 0.7874 0.4064)
			(stroke
				(width 0.1524)
				(type default)
			)
			(layer "F.SilkS")
		)
		(fp_line
			(start -0.67945 0.3048)
			(end -0.67945 -0.305054)
			(stroke
				(width 0.1)
				(type default)
			)
			(layer "F.Fab")
		)
		(fp_line
			(start -0.12065 0.3048)
			(end -0.67945 0.3048)
			(stroke
				(width 0.1)
				(type default)
			)
			(layer "F.Fab")
		)
		(fp_line
			(start 0.120396 0.3048)
			(end 0.120396 0.2794)
			(stroke
				(width 0.1)
				(type default)
			)
			(layer "F.Fab")
		)
		(fp_line
			(start 0.67945 0.3048)
			(end 0.120396 0.3048)
			(stroke
				(width 0.1)
				(type default)
			)
			(layer "F.Fab")
		)
		(fp_line
			(start -0.12065 0.2794)
			(end -0.12065 0.3048)
			(stroke
				(width 0.1)
				(type default)
			)
			(layer "F.Fab")
		)
		(fp_line
			(start 0.120396 0.2794)
			(end -0.12065 0.2794)
			(stroke
				(width 0.1)
				(type default)
			)
			(layer "F.Fab")
		)
		(fp_line
			(start -0.12065 -0.2794)
			(end 0.12065 -0.2794)
			(stroke
				(width 0.1)
				(type default)
			)
			(layer "F.Fab")
		)
		(fp_line
			(start 0.12065 -0.2794)
			(end 0.12065 -0.3048)
			(stroke
				(width 0.1)
				(type default)
			)
			(layer "F.Fab")
		)
		(fp_line
			(start 0.12065 -0.3048)
			(end 0.67945 -0.3048)
			(stroke
				(width 0.1)
				(type default)
			)
			(layer "F.Fab")
		)
		(fp_line
			(start 0.67945 -0.3048)
			(end 0.67945 0.3048)
			(stroke
				(width 0.1)
				(type default)
			)
			(layer "F.Fab")
		)
		(fp_line
			(start -0.67945 -0.305054)
			(end -0.12065 -0.305054)
			(stroke
				(width 0.1)
				(type default)
			)
			(layer "F.Fab")
		)
		(fp_line
			(start -0.12065 -0.305054)
			(end -0.12065 -0.2794)
			(stroke
				(width 0.1)
				(type default)
			)
			(layer "F.Fab")
		)
		(pad "1" smd circle
			(at -0.40005 0 270)
			(size 0 0)
			(layers "F.Cu" "F.Mask" "F.Paste")
			(net "PRSNT_CABLE_GPU_A1_N")
		)
		(pad "2" smd circle
			(at 0.40005 0 270)
			(size 0 0)
			(layers "F.Cu" "F.Mask" "F.Paste")
			(net "GND")
		)
	)
	(footprint ""
		(layer "F.Cu")
		(at 350.78543 -356.668578)
		(property "Reference" "R2369"
			(at 0 0 0)
			(layer "F.SilkS")
			(hide yes)
			(effects
				(font
					(size 1.27 1.27)
				)
			)
		)
		(property "Value" ""
			(at 0 0 0)
			(layer "F.Fab")
			(effects
				(font
					(size 1.27 1.27)
				)
			)
		)
		(duplicate_pad_numbers_are_jumpers no)
		(fp_line
			(start -0.7874 -0.4064)
			(end 0.7874 -0.4064)
			(stroke
				(width 0.1524)
				(type default)
			)
			(layer "F.SilkS")
		)
		(fp_line
			(start -0.7874 0.4064)
			(end -0.7874 -0.4064)
			(stroke
				(width 0.1524)
				(type default)
			)
			(layer "F.SilkS")
		)
		(fp_line
			(start 0.7874 -0.4064)
			(end 0.7874 0.4064)
			(stroke
				(width 0.1524)
				(type default)
			)
			(layer "F.SilkS")
		)
		(fp_line
			(start 0.7874 0.4064)
			(end -0.7874 0.4064)
			(stroke
				(width 0.1524)
				(type default)
			)
			(layer "F.SilkS")
		)
		(fp_line
			(start -0.67945 -0.305054)
			(end -0.12065 -0.305054)
			(stroke
				(width 0.1)
				(type default)
			)
			(layer "F.Fab")
		)
		(fp_line
			(start -0.67945 0.3048)
			(end -0.67945 -0.305054)
			(stroke
				(width 0.1)
				(type default)
			)
			(layer "F.Fab")
		)
		(fp_line
			(start -0.12065 -0.305054)
			(end -0.12065 -0.2794)
			(stroke
				(width 0.1)
				(type default)
			)
			(layer "F.Fab")
		)
		(fp_line
			(start -0.12065 -0.2794)
			(end 0.12065 -0.2794)
			(stroke
				(width 0.1)
				(type default)
			)
			(layer "F.Fab")
		)
		(fp_line
			(start -0.12065 0.2794)
			(end -0.12065 0.3048)
			(stroke
				(width 0.1)
				(type default)
			)
			(layer "F.Fab")
		)
		(fp_line
			(start -0.12065 0.3048)
			(end -0.67945 0.3048)
			(stroke
				(width 0.1)
				(type default)
			)
			(layer "F.Fab")
		)
		(fp_line
			(start 0.120396 0.2794)
			(end -0.12065 0.2794)
			(stroke
				(width 0.1)
				(type default)
			)
			(layer "F.Fab")
		)
		(fp_line
			(start 0.120396 0.3048)
			(end 0.120396 0.2794)
			(stroke
				(width 0.1)
				(type default)
			)
			(layer "F.Fab")
		)
		(fp_line
			(start 0.12065 -0.3048)
			(end 0.67945 -0.3048)
			(stroke
				(width 0.1)
				(type default)
			)
			(layer "F.Fab")
		)
		(fp_line
			(start 0.12065 -0.2794)
			(end 0.12065 -0.3048)
			(stroke
				(width 0.1)
				(type default)
			)
			(layer "F.Fab")
		)
		(fp_line
			(start 0.67945 -0.3048)
			(end 0.67945 0.3048)
			(stroke
				(width 0.1)
				(type default)
			)
			(layer "F.Fab")
		)
		(fp_line
			(start 0.67945 0.3048)
			(end 0.120396 0.3048)
			(stroke
				(width 0.1)
				(type default)
			)
			(layer "F.Fab")
		)
		(pad "1" smd circle
			(at -0.40005 0)
			(size 0 0)
			(layers "F.Cu" "F.Mask" "F.Paste")
			(net "SVID_DIO0_CPU0_R")
		)
		(pad "2" smd circle
			(at 0.40005 0)
			(size 0 0)
			(layers "F.Cu" "F.Mask" "F.Paste")
			(net "SVID_DIO_PVCCIN_CPU0_R")
		)
	)
	(footprint ""
		(layer "F.Cu")
		(at 75.416918 -17.148302 180)
		(property "Reference" "PR3828"
			(at 0 0 180)
			(layer "F.SilkS")
			(hide yes)
			(effects
				(font
					(size 1.27 1.27)
				)
			)
		)
		(property "Value" ""
			(at 0 0 180)
			(layer "F.Fab")
			(effects
				(font
					(size 1.27 1.27)
				)
			)
		)
		(duplicate_pad_numbers_are_jumpers no)
		(fp_line
			(start 0.7874 0.4064)
			(end -0.7874 0.4064)
			(stroke
				(width 0.1524)
				(type default)
			)
			(layer "F.SilkS")
		)
		(fp_line
			(start 0.7874 -0.4064)
			(end 0.7874 0.4064)
			(stroke
				(width 0.1524)
				(type default)
			)
			(layer "F.SilkS")
		)
		(fp_line
			(start -0.7874 0.4064)
			(end -0.7874 -0.4064)
			(stroke
				(width 0.1524)
				(type default)
			)
			(layer "F.SilkS")
		)
		(fp_line
			(start -0.7874 -0.4064)
			(end 0.7874 -0.4064)
			(stroke
				(width 0.1524)
				(type default)
			)
			(layer "F.SilkS")
		)
		(fp_line
			(start 0.67945 0.3048)
			(end 0.120396 0.3048)
			(stroke
				(width 0.1)
				(type default)
			)
			(layer "F.Fab")
		)
		(fp_line
			(start 0.67945 -0.3048)
			(end 0.67945 0.3048)
			(stroke
				(width 0.1)
				(type default)
			)
			(layer "F.Fab")
		)
		(fp_line
			(start 0.12065 -0.2794)
			(end 0.12065 -0.3048)
			(stroke
				(width 0.1)
				(type default)
			)
			(layer "F.Fab")
		)
		(fp_line
			(start 0.12065 -0.3048)
			(end 0.67945 -0.3048)
			(stroke
				(width 0.1)
				(type default)
			)
			(layer "F.Fab")
		)
		(fp_line
			(start 0.120396 0.3048)
			(end 0.120396 0.2794)
			(stroke
				(width 0.1)
				(type default)
			)
			(layer "F.Fab")
		)
		(fp_line
			(start 0.120396 0.2794)
			(end -0.12065 0.2794)
			(stroke
				(width 0.1)
				(type default)
			)
			(layer "F.Fab")
		)
		(fp_line
			(start -0.12065 0.3048)
			(end -0.67945 0.3048)
			(stroke
				(width 0.1)
				(type default)
			)
			(layer "F.Fab")
		)
		(fp_line
			(start -0.12065 0.2794)
			(end -0.12065 0.3048)
			(stroke
				(width 0.1)
				(type default)
			)
			(layer "F.Fab")
		)
		(fp_line
			(start -0.12065 -0.2794)
			(end 0.12065 -0.2794)
			(stroke
				(width 0.1)
				(type default)
			)
			(layer "F.Fab")
		)
		(fp_line
			(start -0.12065 -0.305054)
			(end -0.12065 -0.2794)
			(stroke
				(width 0.1)
				(type default)
			)
			(layer "F.Fab")
		)
		(fp_line
			(start -0.67945 0.3048)
			(end -0.67945 -0.305054)
			(stroke
				(width 0.1)
				(type default)
			)
			(layer "F.Fab")
		)
		(fp_line
			(start -0.67945 -0.305054)
			(end -0.12065 -0.305054)
			(stroke
				(width 0.1)
				(type default)
			)
			(layer "F.Fab")
		)
		(pad "1" smd circle
			(at -0.40005 0 180)
			(size 0 0)
			(layers "F.Cu" "F.Mask" "F.Paste")
			(net "P12V_OCP_OV_2")
		)
		(pad "2" smd circle
			(at 0.40005 0 180)
			(size 0 0)
			(layers "F.Cu" "F.Mask" "F.Paste")
			(net "GND")
		)
	)
	(footprint ""
		(layer "F.Cu")
		(at 395.603984 -16.088614 90)
		(property "Reference" "C843"
			(at 0 0 90)
			(layer "F.SilkS")
			(hide yes)
			(effects
				(font
					(size 1.27 1.27)
				)
			)
		)
		(property "Value" ""
			(at 0 0 90)
			(layer "F.Fab")
			(effects
				(font
					(size 1.27 1.27)
				)
			)
		)
		(duplicate_pad_numbers_are_jumpers no)
		(fp_line
			(start 0.299974 -0.150114)
			(end 0.299974 0.150114)
			(stroke
				(width 0.1)
				(type default)
			)
			(layer "F.Fab")
		)
		(fp_line
			(start -0.299974 -0.150114)
			(end 0.299974 -0.150114)
			(stroke
				(width 0.1)
				(type default)
			)
			(layer "F.Fab")
		)
		(fp_line
			(start 0.299974 0.150114)
			(end -0.299974 0.150114)
			(stroke
				(width 0.1)
				(type default)
			)
			(layer "F.Fab")
		)
		(fp_line
			(start -0.299974 0.150114)
			(end -0.299974 -0.150114)
			(stroke
				(width 0.1)
				(type default)
			)
			(layer "F.Fab")
		)
		(pad "1" smd rect
			(at -0.2667 0 90)
			(size 0.3048 0.381)
			(layers "F.Cu" "F.Mask" "F.Paste")
			(net "P5E_CPU0_PE1_TX_C_DP<13>")
		)
		(pad "2" smd rect
			(at 0.2667 0 90)
			(size 0.3048 0.381)
			(layers "F.Cu" "F.Mask" "F.Paste")
			(net "P5E_CPU0_PE1_TX_DP<13>")
		)
	)
	(footprint ""
		(layer "F.Cu")
		(at 350.691196 -60.591954)
		(property "Reference" "C139"
			(at 0 0 0)
			(layer "F.SilkS")
			(hide yes)
			(effects
				(font
					(size 1.27 1.27)
				)
			)
		)
		(property "Value" ""
			(at 0 0 0)
			(layer "F.Fab")
			(effects
				(font
					(size 1.27 1.27)
				)
			)
		)
		(duplicate_pad_numbers_are_jumpers no)
		(fp_line
			(start -0.299974 -0.150114)
			(end 0.299974 -0.150114)
			(stroke
				(width 0.1)
				(type default)
			)
			(layer "F.Fab")
		)
		(fp_line
			(start -0.299974 0.150114)
			(end -0.299974 -0.150114)
			(stroke
				(width 0.1)
				(type default)
			)
			(layer "F.Fab")
		)
		(fp_line
			(start 0.299974 -0.150114)
			(end 0.299974 0.150114)
			(stroke
				(width 0.1)
				(type default)
			)
			(layer "F.Fab")
		)
		(fp_line
			(start 0.299974 0.150114)
			(end -0.299974 0.150114)
			(stroke
				(width 0.1)
				(type default)
			)
			(layer "F.Fab")
		)
		(pad "1" smd rect
			(at -0.2667 0)
			(size 0.3048 0.381)
			(layers "F.Cu" "F.Mask" "F.Paste")
			(net "DMI_CPU0_PCH_TX_C_DN<7>")
		)
		(pad "2" smd rect
			(at 0.2667 0)
			(size 0.3048 0.381)
			(layers "F.Cu" "F.Mask" "F.Paste")
			(net "DMI_CPU0_PCH_TX_DN<7>")
		)
		(zone
			(layer "In1.Cu")
			(hatch none 0.5)
			(connect_pads
				(clearance 0)
			)
			(min_thickness 0.25)
			(keepout
				(tracks not_allowed)
				(vias allowed)
				(pads allowed)
				(copperpour not_allowed)
				(footprints allowed)
			)
			(placement
				(enabled no)
				(sheetname "")
			)
			(fill
				(thermal_gap 0.5)
				(thermal_bridge_width 0.5)
				(island_removal_mode 0)
			)
			(polygon
				(pts
					(arc
						(start 350.297496 -60.350654)
						(mid 350.243614 -60.372972)
						(end 350.221296 -60.426854)
					)
					(arc
						(start 350.221296 -60.757054)
						(mid 350.243614 -60.810936)
						(end 350.297496 -60.833254)
					)
					(arc
						(start 350.551496 -60.833254)
						(mid 350.605378 -60.810936)
						(end 350.627696 -60.757054)
					)
					(arc
						(start 350.627696 -60.426854)
						(mid 350.605378 -60.372972)
						(end 350.551496 -60.350654)
					)
				)
			)
		)
		(zone
			(layer "In1.Cu")
			(hatch none 0.5)
			(connect_pads
				(clearance 0)
			)
			(min_thickness 0.25)
			(keepout
				(tracks not_allowed)
				(vias allowed)
				(pads allowed)
				(copperpour not_allowed)
				(footprints allowed)
			)
			(placement
				(enabled no)
				(sheetname "")
			)
			(fill
				(thermal_gap 0.5)
				(thermal_bridge_width 0.5)
				(island_removal_mode 0)
			)
			(polygon
				(pts
					(arc
						(start 350.830896 -60.350654)
						(mid 350.777014 -60.372972)
						(end 350.754696 -60.426854)
					)
					(arc
						(start 350.754696 -60.757054)
						(mid 350.777014 -60.810936)
						(end 350.830896 -60.833254)
					)
					(arc
						(start 351.084896 -60.833254)
						(mid 351.138778 -60.810936)
						(end 351.161096 -60.757054)
					)
					(arc
						(start 351.161096 -60.426854)
						(mid 351.138778 -60.372972)
						(end 351.084896 -60.350654)
					)
				)
			)
		)
	)
)
